# T6G (Grand Teton) — schematic netlist excerpt (pin names and nets, part order shuffled) for the footprints in the layout excerpt that follows; sources: Cadence DE-HDL packaged netlist, KiCad conversion of 04192023_DAF0TMB3IC0_F0TG_MB_C_brd_V02_OCP.brd

C1078  Q_CAP  100PF 50V 5% EMPTY  pkg 0402  page 258 : A = P1V2_AUX_ADC_MAM ; B = GND
C2162  Q_CAP  22UF 4V 20% X6S  pkg C0402  page 68 : A = PVDD11_S3_P0 ; B = GND

(kicad_pcb
	(version 20260206)
	(generator "pcbnew")
	(generator_version "10.0")
	(general
		(thickness 1.6)
		(legacy_teardrops no)
	)
	(paper "A4")
	(title_block
		(title "04192023_DAF0TMB3IC0_F0TG_MB_C_brd_V02_OCP.brd")
		(comment 1 "Grand Teton / footprints 6075-6076 of 8354")
	)
	(layers
		(0 "F.Cu" signal "TOP")
		(4 "In1.Cu" signal "GND")
		(6 "In2.Cu" signal "IN1")
		(8 "In3.Cu" signal "GND1")
		(10 "In4.Cu" signal "IN2")
		(12 "In5.Cu" signal "GND2")
		(14 "In6.Cu" signal "IN3")
		(16 "In7.Cu" signal "GND3")
		(18 "In8.Cu" signal "VCC")
		(20 "In9.Cu" signal "VCC1")
		(22 "In10.Cu" signal "GND4")
		(24 "In11.Cu" signal "IN4")
		(26 "In12.Cu" signal "GND5")
		(28 "In13.Cu" signal "IN5")
		(30 "In14.Cu" signal "GND6")
		(32 "In15.Cu" signal "IN6")
		(34 "In16.Cu" signal "GND7")
		(2 "B.Cu" signal "BOTTOM")
		(9 "F.Adhes" user "F.Adhesive")
		(11 "B.Adhes" user "B.Adhesive")
		(13 "F.Paste" user "Package Geometry/Pastemask Top")
		(15 "B.Paste" user "Package Geometry/Pastemask Bottom")
		(5 "F.SilkS" user "Ref Des/Silkscreen Top")
		(7 "B.SilkS" user "Ref Des/Silkscreen Bottom")
		(1 "F.Mask" user "Board Geometry/Soldermask Top")
		(3 "B.Mask" user "Board Geometry/Soldermask Bottom")
		(17 "Dwgs.User" user "User.Drawings")
		(19 "Cmts.User" user "User.Comments")
		(21 "Eco1.User" user "User.Eco1")
		(23 "Eco2.User" user "User.Eco2")
		(25 "Edge.Cuts" user "Board Geometry/Outline")
		(27 "Margin" user)
		(31 "F.CrtYd" user "Package Geometry/Place Bound Top")
		(29 "B.CrtYd" user "Package Geometry/Place Bound Bottom")
		(35 "F.Fab" user "Ref Des/Assembly Top")
		(33 "B.Fab" user "Ref Des/Assembly Bottom")
	)
	(footprint ""
		(layer "B.Cu")
		(at 350.596454 -264.35431)
		(property "Reference" "C2162"
			(at 0 0 0)
			(layer "B.SilkS")
			(hide yes)
			(effects
				(font
					(size 1.27 1.27)
				)
				(justify mirror)
			)
		)
		(property "Value" ""
			(at 0 0 0)
			(layer "B.Fab")
			(effects
				(font
					(size 1.27 1.27)
				)
				(justify mirror)
			)
		)
		(duplicate_pad_numbers_are_jumpers no)
		(fp_line
			(start -0.7874 -0.4064)
			(end -0.7874 0.4064)
			(stroke
				(width 0.1524)
				(type default)
			)
			(layer "B.SilkS")
		)
		(fp_line
			(start -0.7874 0.4064)
			(end 0.7874 0.4064)
			(stroke
				(width 0.1524)
				(type default)
			)
			(layer "B.SilkS")
		)
		(fp_line
			(start 0.7874 -0.4064)
			(end -0.7874 -0.4064)
			(stroke
				(width 0.1524)
				(type default)
			)
			(layer "B.SilkS")
		)
		(fp_line
			(start 0.7874 0.4064)
			(end 0.7874 -0.4064)
			(stroke
				(width 0.1524)
				(type default)
			)
			(layer "B.SilkS")
		)
		(fp_line
			(start -0.67945 -0.3048)
			(end -0.67945 0.3048)
			(stroke
				(width 0.1)
				(type default)
			)
			(layer "B.Fab")
		)
		(fp_line
			(start -0.67945 0.3048)
			(end -0.120396 0.3048)
			(stroke
				(width 0.1)
				(type default)
			)
			(layer "B.Fab")
		)
		(fp_line
			(start -0.12065 -0.3048)
			(end -0.67945 -0.3048)
			(stroke
				(width 0.1)
				(type default)
			)
			(layer "B.Fab")
		)
		(fp_line
			(start -0.12065 -0.2794)
			(end -0.12065 -0.3048)
			(stroke
				(width 0.1)
				(type default)
			)
			(layer "B.Fab")
		)
		(fp_line
			(start -0.120396 0.2794)
			(end 0.12065 0.2794)
			(stroke
				(width 0.1)
				(type default)
			)
			(layer "B.Fab")
		)
		(fp_line
			(start -0.120396 0.3048)
			(end -0.120396 0.2794)
			(stroke
				(width 0.1)
				(type default)
			)
			(layer "B.Fab")
		)
		(fp_line
			(start 0.12065 -0.305054)
			(end 0.12065 -0.2794)
			(stroke
				(width 0.1)
				(type default)
			)
			(layer "B.Fab")
		)
		(fp_line
			(start 0.12065 -0.2794)
			(end -0.12065 -0.2794)
			(stroke
				(width 0.1)
				(type default)
			)
			(layer "B.Fab")
		)
		(fp_line
			(start 0.12065 0.2794)
			(end 0.12065 0.3048)
			(stroke
				(width 0.1)
				(type default)
			)
			(layer "B.Fab")
		)
		(fp_line
			(start 0.12065 0.3048)
			(end 0.67945 0.3048)
			(stroke
				(width 0.1)
				(type default)
			)
			(layer "B.Fab")
		)
		(fp_line
			(start 0.67945 -0.305054)
			(end 0.12065 -0.305054)
			(stroke
				(width 0.1)
				(type default)
			)
			(layer "B.Fab")
		)
		(fp_line
			(start 0.67945 0.3048)
			(end 0.67945 -0.305054)
			(stroke
				(width 0.1)
				(type default)
			)
			(layer "B.Fab")
		)
		(pad "1" smd circle
			(at 0.40005 0 180)
			(size 0 0)
			(layers "B.Cu" "B.Mask" "B.Paste")
			(net "PVDD11_S3_P0")
		)
		(pad "2" smd circle
			(at -0.40005 0 180)
			(size 0 0)
			(layers "B.Cu" "B.Mask" "B.Paste")
			(net "GND")
		)
	)
	(footprint ""
		(layer "B.Cu")
		(at 255.744726 -323.022722 180)
		(property "Reference" "C1078"
			(at 0 0 0)
			(layer "B.SilkS")
			(hide yes)
			(effects
				(font
					(size 1.27 1.27)
				)
				(justify mirror)
			)
		)
		(property "Value" ""
			(at 0 0 0)
			(layer "B.Fab")
			(effects
				(font
					(size 1.27 1.27)
				)
				(justify mirror)
			)
		)
		(duplicate_pad_numbers_are_jumpers no)
		(fp_line
			(start 0.7874 0.4064)
			(end 0.7874 -0.4064)
			(stroke
				(width 0.1524)
				(type default)
			)
			(layer "B.SilkS")
		)
		(fp_line
			(start 0.7874 -0.4064)
			(end -0.7874 -0.4064)
			(stroke
				(width 0.1524)
				(type default)
			)
			(layer "B.SilkS")
		)
		(fp_line
			(start -0.7874 0.4064)
			(end 0.7874 0.4064)
			(stroke
				(width 0.1524)
				(type default)
			)
			(layer "B.SilkS")
		)
		(fp_line
			(start -0.7874 -0.4064)
			(end -0.7874 0.4064)
			(stroke
				(width 0.1524)
				(type default)
			)
			(layer "B.SilkS")
		)
		(fp_line
			(start 0.67945 0.3048)
			(end 0.67945 -0.305054)
			(stroke
				(width 0.1)
				(type default)
			)
			(layer "B.Fab")
		)
		(fp_line
			(start 0.67945 -0.305054)
			(end 0.12065 -0.305054)
			(stroke
				(width 0.1)
				(type default)
			)
			(layer "B.Fab")
		)
		(fp_line
			(start 0.12065 0.3048)
			(end 0.67945 0.3048)
			(stroke
				(width 0.1)
				(type default)
			)
			(layer "B.Fab")
		)
		(fp_line
			(start 0.12065 0.2794)
			(end 0.12065 0.3048)
			(stroke
				(width 0.1)
				(type default)
			)
			(layer "B.Fab")
		)
		(fp_line
			(start 0.12065 -0.2794)
			(end -0.12065 -0.2794)
			(stroke
				(width 0.1)
				(type default)
			)
			(layer "B.Fab")
		)
		(fp_line
			(start 0.12065 -0.305054)
			(end 0.12065 -0.2794)
			(stroke
				(width 0.1)
				(type default)
			)
			(layer "B.Fab")
		)
		(fp_line
			(start -0.120396 0.3048)
			(end -0.120396 0.2794)
			(stroke
				(width 0.1)
				(type default)
			)
			(layer "B.Fab")
		)
		(fp_line
			(start -0.120396 0.2794)
			(end 0.12065 0.2794)
			(stroke
				(width 0.1)
				(type default)
			)
			(layer "B.Fab")
		)
		(fp_line
			(start -0.12065 -0.2794)
			(end -0.12065 -0.3048)
			(stroke
				(width 0.1)
				(type default)
			)
			(layer "B.Fab")
		)
		(fp_line
			(start -0.12065 -0.3048)
			(end -0.67945 -0.3048)
			(stroke
				(width 0.1)
				(type default)
			)
			(layer "B.Fab")
		)
		(fp_line
			(start -0.67945 0.3048)
			(end -0.120396 0.3048)
			(stroke
				(width 0.1)
				(type default)
			)
			(layer "B.Fab")
		)
		(fp_line
			(start -0.67945 -0.3048)
			(end -0.67945 0.3048)
			(stroke
				(width 0.1)
				(type default)
			)
			(layer "B.Fab")
		)
		(pad "1" smd circle
			(at 0.40005 0)
			(size 0 0)
			(layers "B.Cu" "B.Mask" "B.Paste")
			(net "P1V2_AUX_ADC_MAM")
		)
		(pad "2" smd circle
			(at -0.40005 0)
			(size 0 0)
			(layers "B.Cu" "B.Mask" "B.Paste")
			(net "GND")
		)
	)
)
